# T6G (Grand Teton) — schematic netlist excerpt (pin names and nets, part order shuffled) for the footprints in the layout excerpt that follows; sources: Cadence DE-HDL packaged netlist, KiCad conversion of 04192023_DAF0TMB3IC0_F0TG_MB_C_brd_V02_OCP.brd

R8171  Q_RES  49.9 1% CHIP  pkg 0402LF  page 210 : A = SVID_PVDDCR_CPU0_P1_SVTO ; B = SVID_PVDDCR_CPU0_P1_SVTO_R
R3062  Q_RES  2K 1% EMPTY  pkg 0402LF  page 151 : A = SMB_CPU0_CPU1_APML_SDA ; B = P3V3_AUX

(kicad_pcb
	(version 20260206)
	(generator "pcbnew")
	(generator_version "10.0")
	(general
		(thickness 1.6)
		(legacy_teardrops no)
	)
	(paper "A4")
	(title_block
		(title "04192023_DAF0TMB3IC0_F0TG_MB_C_brd_V02_OCP.brd")
		(comment 1 "Grand Teton / footprints 7823-7824 of 8354")
	)
	(layers
		(0 "F.Cu" signal "TOP")
		(4 "In1.Cu" signal "GND")
		(6 "In2.Cu" signal "IN1")
		(8 "In3.Cu" signal "GND1")
		(10 "In4.Cu" signal "IN2")
		(12 "In5.Cu" signal "GND2")
		(14 "In6.Cu" signal "IN3")
		(16 "In7.Cu" signal "GND3")
		(18 "In8.Cu" signal "VCC")
		(20 "In9.Cu" signal "VCC1")
		(22 "In10.Cu" signal "GND4")
		(24 "In11.Cu" signal "IN4")
		(26 "In12.Cu" signal "GND5")
		(28 "In13.Cu" signal "IN5")
		(30 "In14.Cu" signal "GND6")
		(32 "In15.Cu" signal "IN6")
		(34 "In16.Cu" signal "GND7")
		(2 "B.Cu" signal "BOTTOM")
		(9 "F.Adhes" user "F.Adhesive")
		(11 "B.Adhes" user "B.Adhesive")
		(13 "F.Paste" user "Package Geometry/Pastemask Top")
		(15 "B.Paste" user "Package Geometry/Pastemask Bottom")
		(5 "F.SilkS" user "Ref Des/Silkscreen Top")
		(7 "B.SilkS" user "Ref Des/Silkscreen Bottom")
		(1 "F.Mask" user "Board Geometry/Soldermask Top")
		(3 "B.Mask" user "Board Geometry/Soldermask Bottom")
		(17 "Dwgs.User" user "User.Drawings")
		(19 "Cmts.User" user "User.Comments")
		(21 "Eco1.User" user "User.Eco1")
		(23 "Eco2.User" user "User.Eco2")
		(25 "Edge.Cuts" user "Board Geometry/Outline")
		(27 "Margin" user)
		(31 "F.CrtYd" user "Package Geometry/Place Bound Top")
		(29 "B.CrtYd" user "Package Geometry/Place Bound Bottom")
		(35 "F.Fab" user "Ref Des/Assembly Top")
		(33 "B.Fab" user "Ref Des/Assembly Bottom")
	)
	(footprint ""
		(layer "B.Cu")
		(at 180.509164 -23.655782 -90)
		(property "Reference" "R3062"
			(at 0 0 90)
			(layer "B.SilkS")
			(hide yes)
			(effects
				(font
					(size 1.27 1.27)
				)
				(justify mirror)
			)
		)
		(property "Value" ""
			(at 0 0 90)
			(layer "B.Fab")
			(effects
				(font
					(size 1.27 1.27)
				)
				(justify mirror)
			)
		)
		(duplicate_pad_numbers_are_jumpers no)
		(fp_line
			(start -0.7874 0.4064)
			(end 0.7874 0.4064)
			(stroke
				(width 0.1524)
				(type default)
			)
			(layer "B.SilkS")
		)
		(fp_line
			(start 0.7874 0.4064)
			(end 0.7874 -0.4064)
			(stroke
				(width 0.1524)
				(type default)
			)
			(layer "B.SilkS")
		)
		(fp_line
			(start -0.7874 -0.4064)
			(end -0.7874 0.4064)
			(stroke
				(width 0.1524)
				(type default)
			)
			(layer "B.SilkS")
		)
		(fp_line
			(start 0.7874 -0.4064)
			(end -0.7874 -0.4064)
			(stroke
				(width 0.1524)
				(type default)
			)
			(layer "B.SilkS")
		)
		(fp_line
			(start -0.67945 0.3048)
			(end -0.120396 0.3048)
			(stroke
				(width 0.1)
				(type default)
			)
			(layer "B.Fab")
		)
		(fp_line
			(start -0.120396 0.3048)
			(end -0.120396 0.2794)
			(stroke
				(width 0.1)
				(type default)
			)
			(layer "B.Fab")
		)
		(fp_line
			(start 0.12065 0.3048)
			(end 0.67945 0.3048)
			(stroke
				(width 0.1)
				(type default)
			)
			(layer "B.Fab")
		)
		(fp_line
			(start 0.67945 0.3048)
			(end 0.67945 -0.305054)
			(stroke
				(width 0.1)
				(type default)
			)
			(layer "B.Fab")
		)
		(fp_line
			(start -0.120396 0.2794)
			(end 0.12065 0.2794)
			(stroke
				(width 0.1)
				(type default)
			)
			(layer "B.Fab")
		)
		(fp_line
			(start 0.12065 0.2794)
			(end 0.12065 0.3048)
			(stroke
				(width 0.1)
				(type default)
			)
			(layer "B.Fab")
		)
		(fp_line
			(start -0.12065 -0.2794)
			(end -0.12065 -0.3048)
			(stroke
				(width 0.1)
				(type default)
			)
			(layer "B.Fab")
		)
		(fp_line
			(start 0.12065 -0.2794)
			(end -0.12065 -0.2794)
			(stroke
				(width 0.1)
				(type default)
			)
			(layer "B.Fab")
		)
		(fp_line
			(start -0.67945 -0.3048)
			(end -0.67945 0.3048)
			(stroke
				(width 0.1)
				(type default)
			)
			(layer "B.Fab")
		)
		(fp_line
			(start -0.12065 -0.3048)
			(end -0.67945 -0.3048)
			(stroke
				(width 0.1)
				(type default)
			)
			(layer "B.Fab")
		)
		(fp_line
			(start 0.12065 -0.305054)
			(end 0.12065 -0.2794)
			(stroke
				(width 0.1)
				(type default)
			)
			(layer "B.Fab")
		)
		(fp_line
			(start 0.67945 -0.305054)
			(end 0.12065 -0.305054)
			(stroke
				(width 0.1)
				(type default)
			)
			(layer "B.Fab")
		)
		(pad "1" smd circle
			(at 0.40005 0 90)
			(size 0 0)
			(layers "B.Cu" "B.Mask" "B.Paste")
			(net "SMB_CPU0_CPU1_APML_SDA")
		)
		(pad "2" smd circle
			(at -0.40005 0 90)
			(size 0 0)
			(layers "B.Cu" "B.Mask" "B.Paste")
			(net "P3V3_AUX")
		)
	)
	(footprint ""
		(layer "B.Cu")
		(at 90.209878 -148.94941 180)
		(property "Reference" "R8171"
			(at 0 0 0)
			(layer "B.SilkS")
			(hide yes)
			(effects
				(font
					(size 1.27 1.27)
				)
				(justify mirror)
			)
		)
		(property "Value" ""
			(at 0 0 0)
			(layer "B.Fab")
			(effects
				(font
					(size 1.27 1.27)
				)
				(justify mirror)
			)
		)
		(duplicate_pad_numbers_are_jumpers no)
		(fp_line
			(start 0.7874 0.4064)
			(end 0.7874 -0.4064)
			(stroke
				(width 0.1524)
				(type default)
			)
			(layer "B.SilkS")
		)
		(fp_line
			(start 0.7874 -0.4064)
			(end -0.7874 -0.4064)
			(stroke
				(width 0.1524)
				(type default)
			)
			(layer "B.SilkS")
		)
		(fp_line
			(start -0.7874 0.4064)
			(end 0.7874 0.4064)
			(stroke
				(width 0.1524)
				(type default)
			)
			(layer "B.SilkS")
		)
		(fp_line
			(start -0.7874 -0.4064)
			(end -0.7874 0.4064)
			(stroke
				(width 0.1524)
				(type default)
			)
			(layer "B.SilkS")
		)
		(fp_line
			(start 0.67945 0.3048)
			(end 0.67945 -0.305054)
			(stroke
				(width 0.1)
				(type default)
			)
			(layer "B.Fab")
		)
		(fp_line
			(start 0.67945 -0.305054)
			(end 0.12065 -0.305054)
			(stroke
				(width 0.1)
				(type default)
			)
			(layer "B.Fab")
		)
		(fp_line
			(start 0.12065 0.3048)
			(end 0.67945 0.3048)
			(stroke
				(width 0.1)
				(type default)
			)
			(layer "B.Fab")
		)
		(fp_line
			(start 0.12065 0.2794)
			(end 0.12065 0.3048)
			(stroke
				(width 0.1)
				(type default)
			)
			(layer "B.Fab")
		)
		(fp_line
			(start 0.12065 -0.2794)
			(end -0.12065 -0.2794)
			(stroke
				(width 0.1)
				(type default)
			)
			(layer "B.Fab")
		)
		(fp_line
			(start 0.12065 -0.305054)
			(end 0.12065 -0.2794)
			(stroke
				(width 0.1)
				(type default)
			)
			(layer "B.Fab")
		)
		(fp_line
			(start -0.120396 0.3048)
			(end -0.120396 0.2794)
			(stroke
				(width 0.1)
				(type default)
			)
			(layer "B.Fab")
		)
		(fp_line
			(start -0.120396 0.2794)
			(end 0.12065 0.2794)
			(stroke
				(width 0.1)
				(type default)
			)
			(layer "B.Fab")
		)
		(fp_line
			(start -0.12065 -0.2794)
			(end -0.12065 -0.3048)
			(stroke
				(width 0.1)
				(type default)
			)
			(layer "B.Fab")
		)
		(fp_line
			(start -0.12065 -0.3048)
			(end -0.67945 -0.3048)
			(stroke
				(width 0.1)
				(type default)
			)
			(layer "B.Fab")
		)
		(fp_line
			(start -0.67945 0.3048)
			(end -0.120396 0.3048)
			(stroke
				(width 0.1)
				(type default)
			)
			(layer "B.Fab")
		)
		(fp_line
			(start -0.67945 -0.3048)
			(end -0.67945 0.3048)
			(stroke
				(width 0.1)
				(type default)
			)
			(layer "B.Fab")
		)
		(pad "1" smd circle
			(at 0.40005 0)
			(size 0 0)
			(layers "B.Cu" "B.Mask" "B.Paste")
			(net "SVID_PVDDCR_CPU0_P1_SVTO")
		)
		(pad "2" smd circle
			(at -0.40005 0)
			(size 0 0)
			(layers "B.Cu" "B.Mask" "B.Paste")
			(net "SVID_PVDDCR_CPU0_P1_SVTO_R")
		)
	)
)
